# T6G (Grand Teton) — schematic netlist excerpt (pin names and nets, part order shuffled) for the footprints in the layout excerpt that follows; sources: Cadence DE-HDL packaged netlist, KiCad conversion of 04192023_DAF0TMB3IC0_F0TG_MB_C_brd_V02_OCP.brd

R1563  Q_RES  33 5% CHIP  pkg 0402LF  page 81 : A = UART_LS_EN ; B = FM_UART_LS_EN
R949  Q_RES  1K 1% CHIP  pkg 0201LF  page 353 : A = RT_CPU1_P3_ADDR1 ; B = GND
C718  Q_CAP_DIFFBUS  DIFF BUS_0.22UF 6.3V 20% X6S  pkg C0201  page 66 : \1\ = P5E_CPU1_P1_TX_C_DN<11> ; \2\ = P5E_CPU1_P1_TX_DN<11>

(kicad_pcb
	(version 20260206)
	(generator "pcbnew")
	(generator_version "10.0")
	(general
		(thickness 1.6)
		(legacy_teardrops no)
	)
	(paper "A4")
	(title_block
		(title "04192023_DAF0TMB3IC0_F0TG_MB_C_brd_V02_OCP.brd")
		(comment 1 "Grand Teton / footprints 362-364 of 8354")
	)
	(layers
		(0 "F.Cu" signal "TOP")
		(4 "In1.Cu" signal "GND")
		(6 "In2.Cu" signal "IN1")
		(8 "In3.Cu" signal "GND1")
		(10 "In4.Cu" signal "IN2")
		(12 "In5.Cu" signal "GND2")
		(14 "In6.Cu" signal "IN3")
		(16 "In7.Cu" signal "GND3")
		(18 "In8.Cu" signal "VCC")
		(20 "In9.Cu" signal "VCC1")
		(22 "In10.Cu" signal "GND4")
		(24 "In11.Cu" signal "IN4")
		(26 "In12.Cu" signal "GND5")
		(28 "In13.Cu" signal "IN5")
		(30 "In14.Cu" signal "GND6")
		(32 "In15.Cu" signal "IN6")
		(34 "In16.Cu" signal "GND7")
		(2 "B.Cu" signal "BOTTOM")
		(9 "F.Adhes" user "F.Adhesive")
		(11 "B.Adhes" user "B.Adhesive")
		(13 "F.Paste" user "Package Geometry/Pastemask Top")
		(15 "B.Paste" user "Package Geometry/Pastemask Bottom")
		(5 "F.SilkS" user "Ref Des/Silkscreen Top")
		(7 "B.SilkS" user "Ref Des/Silkscreen Bottom")
		(1 "F.Mask" user "Board Geometry/Soldermask Top")
		(3 "B.Mask" user "Board Geometry/Soldermask Bottom")
		(17 "Dwgs.User" user "User.Drawings")
		(19 "Cmts.User" user "User.Comments")
		(21 "Eco1.User" user "User.Eco1")
		(23 "Eco2.User" user "User.Eco2")
		(25 "Edge.Cuts" user "Board Geometry/Outline")
		(27 "Margin" user)
		(31 "F.CrtYd" user "Package Geometry/Place Bound Top")
		(29 "B.CrtYd" user "Package Geometry/Place Bound Bottom")
		(35 "F.Fab" user "Ref Des/Assembly Top")
		(33 "B.Fab" user "Ref Des/Assembly Bottom")
	)
	(footprint ""
		(layer "F.Cu")
		(at 139.544552 -382.00584)
		(property "Reference" "R949"
			(at 0 0 0)
			(layer "F.SilkS")
			(hide yes)
			(effects
				(font
					(size 1.27 1.27)
				)
			)
		)
		(property "Value" ""
			(at 0 0 0)
			(layer "F.Fab")
			(effects
				(font
					(size 1.27 1.27)
				)
			)
		)
		(duplicate_pad_numbers_are_jumpers no)
		(fp_line
			(start -0.32512 -0.175006)
			(end 0.32512 -0.175006)
			(stroke
				(width 0.1)
				(type default)
			)
			(layer "F.Fab")
		)
		(fp_line
			(start -0.32512 0.175006)
			(end -0.32512 -0.175006)
			(stroke
				(width 0.1)
				(type default)
			)
			(layer "F.Fab")
		)
		(fp_line
			(start 0.32512 -0.175006)
			(end 0.32512 0.175006)
			(stroke
				(width 0.1)
				(type default)
			)
			(layer "F.Fab")
		)
		(fp_line
			(start 0.32512 0.175006)
			(end -0.32512 0.175006)
			(stroke
				(width 0.1)
				(type default)
			)
			(layer "F.Fab")
		)
		(pad "1" smd rect
			(at -0.2667 0)
			(size 0.3048 0.381)
			(layers "F.Cu" "F.Mask" "F.Paste")
			(net "RT_CPU1_P3_ADDR1")
		)
		(pad "2" smd rect
			(at 0.2667 0 180)
			(size 0.3048 0.381)
			(layers "F.Cu" "F.Mask" "F.Paste")
			(net "GND")
		)
	)
	(footprint ""
		(layer "F.Cu")
		(at 96.853502 -373.03583 -90)
		(property "Reference" "C718"
			(at 0 0 270)
			(layer "F.SilkS")
			(hide yes)
			(effects
				(font
					(size 1.27 1.27)
				)
			)
		)
		(property "Value" ""
			(at 0 0 270)
			(layer "F.Fab")
			(effects
				(font
					(size 1.27 1.27)
				)
			)
		)
		(duplicate_pad_numbers_are_jumpers no)
		(fp_line
			(start -0.299974 0.150114)
			(end -0.299974 -0.150114)
			(stroke
				(width 0.1)
				(type default)
			)
			(layer "F.Fab")
		)
		(fp_line
			(start 0.299974 0.150114)
			(end -0.299974 0.150114)
			(stroke
				(width 0.1)
				(type default)
			)
			(layer "F.Fab")
		)
		(fp_line
			(start -0.299974 -0.150114)
			(end 0.299974 -0.150114)
			(stroke
				(width 0.1)
				(type default)
			)
			(layer "F.Fab")
		)
		(fp_line
			(start 0.299974 -0.150114)
			(end 0.299974 0.150114)
			(stroke
				(width 0.1)
				(type default)
			)
			(layer "F.Fab")
		)
		(pad "1" smd rect
			(at -0.2667 0 270)
			(size 0.3048 0.381)
			(layers "F.Cu" "F.Mask" "F.Paste")
			(net "P5E_CPU1_P1_TX_C_DN<11>")
		)
		(pad "2" smd rect
			(at 0.2667 0 270)
			(size 0.3048 0.381)
			(layers "F.Cu" "F.Mask" "F.Paste")
			(net "P5E_CPU1_P1_TX_DN<11>")
		)
	)
	(footprint ""
		(layer "F.Cu")
		(at 204.954886 -111.665512 180)
		(property "Reference" "R1563"
			(at 0 0 180)
			(layer "F.SilkS")
			(hide yes)
			(effects
				(font
					(size 1.27 1.27)
				)
			)
		)
		(property "Value" ""
			(at 0 0 180)
			(layer "F.Fab")
			(effects
				(font
					(size 1.27 1.27)
				)
			)
		)
		(duplicate_pad_numbers_are_jumpers no)
		(fp_line
			(start 0.7874 0.4064)
			(end -0.7874 0.4064)
			(stroke
				(width 0.1524)
				(type default)
			)
			(layer "F.SilkS")
		)
		(fp_line
			(start 0.7874 -0.4064)
			(end 0.7874 0.4064)
			(stroke
				(width 0.1524)
				(type default)
			)
			(layer "F.SilkS")
		)
		(fp_line
			(start -0.7874 0.4064)
			(end -0.7874 -0.4064)
			(stroke
				(width 0.1524)
				(type default)
			)
			(layer "F.SilkS")
		)
		(fp_line
			(start -0.7874 -0.4064)
			(end 0.7874 -0.4064)
			(stroke
				(width 0.1524)
				(type default)
			)
			(layer "F.SilkS")
		)
		(fp_line
			(start 0.67945 0.3048)
			(end 0.120396 0.3048)
			(stroke
				(width 0.1)
				(type default)
			)
			(layer "F.Fab")
		)
		(fp_line
			(start 0.67945 -0.3048)
			(end 0.67945 0.3048)
			(stroke
				(width 0.1)
				(type default)
			)
			(layer "F.Fab")
		)
		(fp_line
			(start 0.12065 -0.2794)
			(end 0.12065 -0.3048)
			(stroke
				(width 0.1)
				(type default)
			)
			(layer "F.Fab")
		)
		(fp_line
			(start 0.12065 -0.3048)
			(end 0.67945 -0.3048)
			(stroke
				(width 0.1)
				(type default)
			)
			(layer "F.Fab")
		)
		(fp_line
			(start 0.120396 0.3048)
			(end 0.120396 0.2794)
			(stroke
				(width 0.1)
				(type default)
			)
			(layer "F.Fab")
		)
		(fp_line
			(start 0.120396 0.2794)
			(end -0.12065 0.2794)
			(stroke
				(width 0.1)
				(type default)
			)
			(layer "F.Fab")
		)
		(fp_line
			(start -0.12065 0.3048)
			(end -0.67945 0.3048)
			(stroke
				(width 0.1)
				(type default)
			)
			(layer "F.Fab")
		)
		(fp_line
			(start -0.12065 0.2794)
			(end -0.12065 0.3048)
			(stroke
				(width 0.1)
				(type default)
			)
			(layer "F.Fab")
		)
		(fp_line
			(start -0.12065 -0.2794)
			(end 0.12065 -0.2794)
			(stroke
				(width 0.1)
				(type default)
			)
			(layer "F.Fab")
		)
		(fp_line
			(start -0.12065 -0.305054)
			(end -0.12065 -0.2794)
			(stroke
				(width 0.1)
				(type default)
			)
			(layer "F.Fab")
		)
		(fp_line
			(start -0.67945 0.3048)
			(end -0.67945 -0.305054)
			(stroke
				(width 0.1)
				(type default)
			)
			(layer "F.Fab")
		)
		(fp_line
			(start -0.67945 -0.305054)
			(end -0.12065 -0.305054)
			(stroke
				(width 0.1)
				(type default)
			)
			(layer "F.Fab")
		)
		(pad "1" smd circle
			(at -0.40005 0 180)
			(size 0 0)
			(layers "F.Cu" "F.Mask" "F.Paste")
			(net "UART_LS_EN")
		)
		(pad "2" smd circle
			(at 0.40005 0 180)
			(size 0 0)
			(layers "F.Cu" "F.Mask" "F.Paste")
			(net "FM_UART_LS_EN")
		)
	)
)
